# BASEBOARD_FAB2 (Tioga Pass) — schematic netlist excerpt (pin names and nets, part order shuffled) for the footprints in the layout excerpt that follows; sources: Cadence DE-HDL packaged netlist, KiCad conversion of Wiwynn_Tioga_Pass_MB.brd

CT64  CAP  1000PF 50V 10% X7R  pkg 0402LF  page 236 : A = A_TSENSE_PVNN_PCH_TMON ; B = GND
C8B7  CAP_A  0.1UF 16V 10% X7R  pkg 0402V  page 198 : A = P5V ; B = GND
C7G21  CAP  0.22UF 16V 10% X7R  pkg 0402  page 105 : A = P3E_CPU0_PE2_SS_TXP<7> ; B = P3E_CPU0_PE2_SS_C_TXP<7>

(kicad_pcb
	(version 20260206)
	(generator "pcbnew")
	(generator_version "10.0")
	(general
		(thickness 1.6)
		(legacy_teardrops no)
	)
	(paper "A4")
	(title_block
		(title "Wiwynn_Tioga_Pass_MB.brd")
		(comment 1 "Tioga Pass / footprints 1121-1123 of 4770")
	)
	(layers
		(0 "F.Cu" signal "TOP")
		(4 "In1.Cu" signal "L2GND")
		(6 "In2.Cu" signal "L3")
		(8 "In3.Cu" signal "L4GND")
		(10 "In4.Cu" signal "L5")
		(12 "In5.Cu" signal "L6GND")
		(14 "In6.Cu" signal "L7VCC")
		(16 "In7.Cu" signal "L8VCC")
		(18 "In8.Cu" signal "L9GND")
		(20 "In9.Cu" signal "L10")
		(22 "In10.Cu" signal "L11GND")
		(24 "In11.Cu" signal "L12")
		(26 "In12.Cu" signal "L13GND")
		(2 "B.Cu" signal "BOTTOM")
		(9 "F.Adhes" user "F.Adhesive")
		(11 "B.Adhes" user "B.Adhesive")
		(13 "F.Paste" user "Package Geometry/Pastemask Top")
		(15 "B.Paste" user "Package Geometry/Pastemask Bottom")
		(5 "F.SilkS" user "Ref Des/Silkscreen Top")
		(7 "B.SilkS" user "Ref Des/Silkscreen Bottom")
		(1 "F.Mask" user "Board Geometry/Soldermask Top")
		(3 "B.Mask" user "Board Geometry/Soldermask Bottom")
		(17 "Dwgs.User" user "User.Drawings")
		(19 "Cmts.User" user "User.Comments")
		(21 "Eco1.User" user "User.Eco1")
		(23 "Eco2.User" user "User.Eco2")
		(25 "Edge.Cuts" user "Board Geometry/Outline")
		(27 "Margin" user)
		(31 "F.CrtYd" user "Package Geometry/Place Bound Top")
		(29 "B.CrtYd" user "Package Geometry/Place Bound Bottom")
		(35 "F.Fab" user "Ref Des/Assembly Top")
		(33 "B.Fab" user "Ref Des/Assembly Bottom")
	)
	(footprint ""
		(layer "F.Cu")
		(at 393.254992 -10.917936)
		(property "Reference" "C7G21"
			(at 0 0 0)
			(layer "F.SilkS")
			(hide yes)
			(effects
				(font
					(size 1.27 1.27)
				)
			)
		)
		(property "Value" ""
			(at 0 0 0)
			(layer "F.Fab")
			(effects
				(font
					(size 1.27 1.27)
				)
			)
		)
		(duplicate_pad_numbers_are_jumpers no)
		(fp_rect
			(start -0.3048 0.9906)
			(end 0.3048 -0.1016)
			(stroke
				(width 0)
				(type default)
			)
			(fill no)
			(layer "F.CrtYd")
		)
		(fp_line
			(start -0.3048 -0.1016)
			(end -0.3048 0.9906)
			(stroke
				(width 0.1)
				(type default)
			)
			(layer "F.Fab")
		)
		(fp_line
			(start -0.3048 0.9906)
			(end 0.3048 0.9906)
			(stroke
				(width 0.1)
				(type default)
			)
			(layer "F.Fab")
		)
		(fp_line
			(start 0.3048 -0.1016)
			(end -0.3048 -0.1016)
			(stroke
				(width 0.1)
				(type default)
			)
			(layer "F.Fab")
		)
		(fp_line
			(start 0.3048 0.9906)
			(end 0.3048 -0.1016)
			(stroke
				(width 0.1)
				(type default)
			)
			(layer "F.Fab")
		)
		(pad "1" smd rect
			(at 0 0)
			(size 0.508 0.508)
			(layers "F.Cu" "F.Mask" "F.Paste")
			(net "P3E_CPU0_PE2_SS_TXP<7>")
		)
		(pad "2" smd rect
			(at 0 0.889)
			(size 0.508 0.508)
			(layers "F.Cu" "F.Mask" "F.Paste")
			(net "P3E_CPU0_PE2_SS_C_TXP<7>")
		)
		(zone
			(layer "F.Cu")
			(hatch none 0.5)
			(connect_pads
				(clearance 0)
			)
			(min_thickness 0.25)
			(keepout
				(tracks not_allowed)
				(vias allowed)
				(pads allowed)
				(copperpour not_allowed)
				(footprints allowed)
			)
			(placement
				(enabled no)
				(sheetname "")
			)
			(fill
				(thermal_gap 0.5)
				(thermal_bridge_width 0.5)
				(island_removal_mode 0)
			)
			(polygon
				(pts
					(xy 393.000992 -10.282936) (xy 393.508992 -10.282936) (xy 393.508992 -10.663936) (xy 393.000992 -10.663936)
				)
			)
		)
		(zone
			(layer "F.Cu")
			(hatch none 0.5)
			(connect_pads
				(clearance 0)
			)
			(min_thickness 0.25)
			(keepout
				(tracks allowed)
				(vias not_allowed)
				(pads allowed)
				(copperpour not_allowed)
				(footprints allowed)
			)
			(placement
				(enabled no)
				(sheetname "")
			)
			(fill
				(thermal_gap 0.5)
				(thermal_bridge_width 0.5)
				(island_removal_mode 0)
			)
			(polygon
				(pts
					(xy 393.000992 -10.282936) (xy 393.508992 -10.282936) (xy 393.508992 -10.663936) (xy 393.000992 -10.663936)
				)
			)
		)
	)
	(footprint ""
		(layer "F.Cu")
		(at 437.9468 -128.6764 180)
		(property "Reference" "C8B7"
			(at 0 0 180)
			(layer "F.SilkS")
			(hide yes)
			(effects
				(font
					(size 1.27 1.27)
				)
			)
		)
		(property "Value" ""
			(at 0 0 180)
			(layer "F.Fab")
			(effects
				(font
					(size 1.27 1.27)
				)
			)
		)
		(duplicate_pad_numbers_are_jumpers no)
		(fp_poly
			(pts
				(xy 0.3048 -0.1016) (xy 0.3048 0.9906) (xy -0.3048 0.9906) (xy -0.3048 -0.1016)
			)
			(stroke
				(width 0)
				(type default)
			)
			(fill no)
			(layer "F.CrtYd")
		)
		(fp_line
			(start 0.3048 0.9906)
			(end 0.3048 -0.1016)
			(stroke
				(width 0.1)
				(type default)
			)
			(layer "F.Fab")
		)
		(fp_line
			(start 0.3048 -0.1016)
			(end -0.3048 -0.1016)
			(stroke
				(width 0.1)
				(type default)
			)
			(layer "F.Fab")
		)
		(fp_line
			(start -0.3048 0.9906)
			(end 0.3048 0.9906)
			(stroke
				(width 0.1)
				(type default)
			)
			(layer "F.Fab")
		)
		(fp_line
			(start -0.3048 -0.1016)
			(end -0.3048 0.9906)
			(stroke
				(width 0.1)
				(type default)
			)
			(layer "F.Fab")
		)
		(pad "1" smd rect
			(at 0 0 180)
			(size 0.508 0.508)
			(layers "F.Cu" "F.Mask" "F.Paste")
			(net "P5V")
		)
		(pad "2" smd rect
			(at 0 0.889 180)
			(size 0.508 0.508)
			(layers "F.Cu" "F.Mask" "F.Paste")
			(net "GND")
		)
		(zone
			(layer "F.Cu")
			(hatch none 0.5)
			(connect_pads
				(clearance 0)
			)
			(min_thickness 0.25)
			(keepout
				(tracks not_allowed)
				(vias allowed)
				(pads allowed)
				(copperpour not_allowed)
				(footprints allowed)
			)
			(placement
				(enabled no)
				(sheetname "")
			)
			(fill
				(thermal_gap 0.5)
				(thermal_bridge_width 0.5)
				(island_removal_mode 0)
			)
			(polygon
				(pts
					(xy 438.2008 -129.3114) (xy 437.6928 -129.3114) (xy 437.6928 -128.9304) (xy 438.2008 -128.9304)
				)
			)
		)
		(zone
			(layer "F.Cu")
			(hatch none 0.5)
			(connect_pads
				(clearance 0)
			)
			(min_thickness 0.25)
			(keepout
				(tracks allowed)
				(vias not_allowed)
				(pads allowed)
				(copperpour not_allowed)
				(footprints allowed)
			)
			(placement
				(enabled no)
				(sheetname "")
			)
			(fill
				(thermal_gap 0.5)
				(thermal_bridge_width 0.5)
				(island_removal_mode 0)
			)
			(polygon
				(pts
					(xy 438.2008 -128.9304) (xy 437.6928 -128.9304) (xy 437.6928 -129.3114) (xy 438.2008 -129.3114)
				)
			)
		)
	)
	(footprint ""
		(layer "F.Cu")
		(at 375.5136 -158.2166 -90)
		(property "Reference" "CT64"
			(at 4.90347 8.7884 0)
			(unlocked yes)
			(layer "F.SilkS")
			(effects
				(font
					(size 0.7874 0.5842)
					(thickness 0.1524)
				)
				(justify left)
			)
		)
		(property "Value" ""
			(at 0 0 270)
			(layer "F.Fab")
			(effects
				(font
					(size 1.27 1.27)
				)
			)
		)
		(duplicate_pad_numbers_are_jumpers no)
		(fp_poly
			(pts
				(xy 0.3048 -0.1016) (xy 0.3048 0.9906) (xy -0.3048 0.9906) (xy -0.3048 -0.1016)
			)
			(stroke
				(width 0)
				(type default)
			)
			(fill no)
			(layer "F.CrtYd")
		)
		(fp_line
			(start -0.3048 0.9906)
			(end 0.3048 0.9906)
			(stroke
				(width 0.1)
				(type default)
			)
			(layer "F.Fab")
		)
		(fp_line
			(start 0.3048 0.9906)
			(end 0.3048 -0.1016)
			(stroke
				(width 0.1)
				(type default)
			)
			(layer "F.Fab")
		)
		(fp_line
			(start -0.3048 -0.1016)
			(end -0.3048 0.9906)
			(stroke
				(width 0.1)
				(type default)
			)
			(layer "F.Fab")
		)
		(fp_line
			(start 0.3048 -0.1016)
			(end -0.3048 -0.1016)
			(stroke
				(width 0.1)
				(type default)
			)
			(layer "F.Fab")
		)
		(pad "1" smd rect
			(at 0 0 270)
			(size 0.508 0.508)
			(layers "F.Cu" "F.Mask" "F.Paste")
			(net "A_TSENSE_PVNN_PCH_TMON")
		)
		(pad "2" smd rect
			(at 0 0.889 270)
			(size 0.508 0.508)
			(layers "F.Cu" "F.Mask" "F.Paste")
			(net "GND")
		)
		(zone
			(layer "F.Cu")
			(hatch none 0.5)
			(connect_pads
				(clearance 0)
			)
			(min_thickness 0.25)
			(keepout
				(tracks not_allowed)
				(vias allowed)
				(pads allowed)
				(copperpour not_allowed)
				(footprints allowed)
			)
			(placement
				(enabled no)
				(sheetname "")
			)
			(fill
				(thermal_gap 0.5)
				(thermal_bridge_width 0.5)
				(island_removal_mode 0)
			)
			(polygon
				(pts
					(xy 374.8786 -158.4706) (xy 374.8786 -157.9626) (xy 375.2596 -157.9626) (xy 375.2596 -158.4706)
				)
			)
		)
		(zone
			(layer "F.Cu")
			(hatch none 0.5)
			(connect_pads
				(clearance 0)
			)
			(min_thickness 0.25)
			(keepout
				(tracks allowed)
				(vias not_allowed)
				(pads allowed)
				(copperpour not_allowed)
				(footprints allowed)
			)
			(placement
				(enabled no)
				(sheetname "")
			)
			(fill
				(thermal_gap 0.5)
				(thermal_bridge_width 0.5)
				(island_removal_mode 0)
			)
			(polygon
				(pts
					(xy 375.2596 -158.4706) (xy 375.2596 -157.9626) (xy 374.8786 -157.9626) (xy 374.8786 -158.4706)
				)
			)
		)
	)
)
